(kicad_pcb
	(version 20260206)
	(generator "pcbnew")
	(generator_version "10.0")
	(general
		(thickness 1.6)
		(legacy_teardrops no)
	)
	(paper "A4")
	(title_block
		(title "01162023_DA0F0TEBIF0_F0T_Expander_BD_F_brd_V02_OCP.brd")
		(comment 1 "Grand Teton / footprints 3911-3917 of 9728")
	)
	(layers
		(0 "F.Cu" signal "TOP")
		(4 "In1.Cu" signal "GND")
		(6 "In2.Cu" signal "VCC")
		(8 "In3.Cu" signal "VCC1")
		(10 "In4.Cu" signal "GND1")
		(12 "In5.Cu" signal "IN1")
		(14 "In6.Cu" signal "GND2")
		(16 "In7.Cu" signal "IN2")
		(18 "In8.Cu" signal "GND3")
		(20 "In9.Cu" signal "IN3")
		(22 "In10.Cu" signal "GND4")
		(24 "In11.Cu" signal "IN4")
		(26 "In12.Cu" signal "GND5")
		(28 "In13.Cu" signal "IN5")
		(30 "In14.Cu" signal "GND6")
		(32 "In15.Cu" signal "IN6")
		(34 "In16.Cu" signal "GND7")
		(2 "B.Cu" signal "BOTTOM")
		(9 "F.Adhes" user "F.Adhesive")
		(11 "B.Adhes" user "B.Adhesive")
		(13 "F.Paste" user "Package Geometry/Pastemask Top")
		(15 "B.Paste" user "Package Geometry/Pastemask Bottom")
		(5 "F.SilkS" user "Ref Des/Silkscreen Top")
		(7 "B.SilkS" user "Ref Des/Silkscreen Bottom")
		(1 "F.Mask" user "Board Geometry/Soldermask Top")
		(3 "B.Mask" user "Board Geometry/Soldermask Bottom")
		(17 "Dwgs.User" user "User.Drawings")
		(19 "Cmts.User" user "User.Comments")
		(21 "Eco1.User" user "User.Eco1")
		(23 "Eco2.User" user "User.Eco2")
		(25 "Edge.Cuts" user "Board Geometry/Outline")
		(27 "Margin" user)
		(31 "F.CrtYd" user "Package Geometry/Place Bound Top")
		(29 "B.CrtYd" user "Package Geometry/Place Bound Bottom")
		(35 "F.Fab" user "Ref Des/Assembly Top")
		(33 "B.Fab" user "Ref Des/Assembly Bottom")
	)
	(footprint ""
		(layer "F.Cu")
		(at 264.616946 -308.852062 -135)
		(property "Reference" "R1395"
			(at 0 0 225)
			(layer "F.SilkS")
			(hide yes)
			(effects
				(font
					(size 1.27 1.27)
				)
			)
		)
		(property "Value" ""
			(at 0 0 225)
			(layer "F.Fab")
			(effects
				(font
					(size 1.27 1.27)
				)
			)
		)
		(duplicate_pad_numbers_are_jumpers no)
		(fp_line
			(start 0.787389 0.406267)
			(end -0.787389 0.406267)
			(stroke
				(width 0.1524)
				(type default)
			)
			(layer "F.SilkS")
		)
		(fp_line
			(start 0.787389 -0.406267)
			(end 0.787389 0.406267)
			(stroke
				(width 0.1524)
				(type default)
			)
			(layer "F.SilkS")
		)
		(fp_line
			(start -0.787389 0.406267)
			(end -0.787389 -0.406267)
			(stroke
				(width 0.1524)
				(type default)
			)
			(layer "F.SilkS")
		)
		(fp_line
			(start -0.787389 -0.406267)
			(end 0.787389 -0.406267)
			(stroke
				(width 0.1524)
				(type default)
			)
			(layer "F.SilkS")
		)
		(fp_line
			(start 0.679446 0.30479)
			(end 0.120515 0.30479)
			(stroke
				(width 0.1)
				(type default)
			)
			(layer "F.Fab")
		)
		(fp_line
			(start 0.120515 0.30479)
			(end 0.120335 0.279466)
			(stroke
				(width 0.1)
				(type default)
			)
			(layer "F.Fab")
		)
		(fp_line
			(start 0.120335 0.279466)
			(end -0.120695 0.279466)
			(stroke
				(width 0.1)
				(type default)
			)
			(layer "F.Fab")
		)
		(fp_line
			(start 0.679446 -0.30479)
			(end 0.679446 0.30479)
			(stroke
				(width 0.1)
				(type default)
			)
			(layer "F.Fab")
		)
		(fp_line
			(start -0.120515 0.30479)
			(end -0.679446 0.30479)
			(stroke
				(width 0.1)
				(type default)
			)
			(layer "F.Fab")
		)
		(fp_line
			(start -0.120695 0.279466)
			(end -0.120515 0.30479)
			(stroke
				(width 0.1)
				(type default)
			)
			(layer "F.Fab")
		)
		(fp_line
			(start 0.120695 -0.279466)
			(end 0.120515 -0.30479)
			(stroke
				(width 0.1)
				(type default)
			)
			(layer "F.Fab")
		)
		(fp_line
			(start 0.120515 -0.30479)
			(end 0.679446 -0.30479)
			(stroke
				(width 0.1)
				(type default)
			)
			(layer "F.Fab")
		)
		(fp_line
			(start -0.679446 0.30479)
			(end -0.679446 -0.305149)
			(stroke
				(width 0.1)
				(type default)
			)
			(layer "F.Fab")
		)
		(fp_line
			(start -0.120695 -0.279466)
			(end 0.120695 -0.279466)
			(stroke
				(width 0.1)
				(type default)
			)
			(layer "F.Fab")
		)
		(fp_line
			(start -0.120695 -0.304969)
			(end -0.120695 -0.279466)
			(stroke
				(width 0.1)
				(type default)
			)
			(layer "F.Fab")
		)
		(fp_line
			(start -0.679446 -0.305149)
			(end -0.120695 -0.304969)
			(stroke
				(width 0.1)
				(type default)
			)
			(layer "F.Fab")
		)
		(pad "1" smd circle
			(at -0.40005 0 225)
			(size 0 0)
			(layers "F.Cu" "F.Mask" "F.Paste")
			(net "PU_PEX2_ATPG_MODE_L")
		)
		(pad "2" smd circle
			(at 0.40005 0 225)
			(size 0 0)
			(layers "F.Cu" "F.Mask" "F.Paste")
			(net "P1V8_PEX")
		)
	)
	(footprint ""
		(layer "F.Cu")
		(at 43.94708 -55.63489 90)
		(property "Reference" "PC645"
			(at 0 0 90)
			(layer "F.SilkS")
			(hide yes)
			(effects
				(font
					(size 1.27 1.27)
				)
			)
		)
		(property "Value" ""
			(at 0 0 90)
			(layer "F.Fab")
			(effects
				(font
					(size 1.27 1.27)
				)
			)
		)
		(duplicate_pad_numbers_are_jumpers no)
		(fp_line
			(start 1.524 -0.762)
			(end 1.524 0.762)
			(stroke
				(width 0.1524)
				(type default)
			)
			(layer "F.SilkS")
		)
		(fp_line
			(start -1.524 -0.762)
			(end 1.524 -0.762)
			(stroke
				(width 0.1524)
				(type default)
			)
			(layer "F.SilkS")
		)
		(fp_line
			(start 1.524 0.762)
			(end -1.524 0.762)
			(stroke
				(width 0.1524)
				(type default)
			)
			(layer "F.SilkS")
		)
		(fp_line
			(start -1.524 0.762)
			(end -1.524 -0.762)
			(stroke
				(width 0.1524)
				(type default)
			)
			(layer "F.SilkS")
		)
		(fp_line
			(start 1.1049 -0.724916)
			(end -1.1049 -0.724916)
			(stroke
				(width 0.1)
				(type default)
			)
			(layer "F.Fab")
		)
		(fp_line
			(start -1.1049 -0.724916)
			(end -1.1049 0.724916)
			(stroke
				(width 0.1)
				(type default)
			)
			(layer "F.Fab")
		)
		(fp_line
			(start 1.1049 0.724916)
			(end 1.1049 -0.724916)
			(stroke
				(width 0.1)
				(type default)
			)
			(layer "F.Fab")
		)
		(fp_line
			(start -1.1049 0.724916)
			(end 1.1049 0.724916)
			(stroke
				(width 0.1)
				(type default)
			)
			(layer "F.Fab")
		)
		(pad "1" smd rect
			(at -0.889 0 270)
			(size 1.016 1.27)
			(layers "F.Cu" "F.Mask" "F.Paste")
			(net "P12V_SSD1_R")
		)
		(pad "2" smd rect
			(at 0.889 0 270)
			(size 1.016 1.27)
			(layers "F.Cu" "F.Mask" "F.Paste")
			(net "GND")
		)
	)
	(footprint ""
		(layer "F.Cu")
		(at 286.982408 -29.875734)
		(property "Reference" "PU129"
			(at -3.447796 -2.207768 90)
			(unlocked yes)
			(layer "F.SilkS")
			(effects
				(font
					(size 0.7874 0.5842)
					(thickness 0.1524)
				)
			)
		)
		(property "Value" ""
			(at 0 0 0)
			(layer "F.Fab")
			(effects
				(font
					(size 1.27 1.27)
				)
			)
		)
		(duplicate_pad_numbers_are_jumpers no)
		(fp_line
			(start -1.239774 -1.495298)
			(end 1.239774 -1.495298)
			(stroke
				(width 0.1524)
				(type default)
			)
			(layer "F.SilkS")
		)
		(fp_line
			(start -1.239774 1.495298)
			(end -1.239774 -1.495298)
			(stroke
				(width 0.1524)
				(type default)
			)
			(layer "F.SilkS")
		)
		(fp_line
			(start 1.239774 -1.495298)
			(end 1.239774 1.495298)
			(stroke
				(width 0.1524)
				(type default)
			)
			(layer "F.SilkS")
		)
		(fp_line
			(start 1.239774 1.495298)
			(end -1.239774 1.495298)
			(stroke
				(width 0.1524)
				(type default)
			)
			(layer "F.SilkS")
		)
		(fp_poly
			(pts
				(xy -2.232914 -1.512824) (xy -2.951226 -0.794258) (xy -1.873504 -0.435102)
			)
			(stroke
				(width 0)
				(type default)
			)
			(fill yes)
			(layer "F.SilkS")
		)
		(fp_line
			(start -0.8001 -1.050036)
			(end 0.8001 -1.050036)
			(stroke
				(width 0.1)
				(type default)
			)
			(layer "F.Fab")
		)
		(fp_line
			(start -0.8001 1.050036)
			(end -0.8001 -1.050036)
			(stroke
				(width 0.1)
				(type default)
			)
			(layer "F.Fab")
		)
		(fp_line
			(start 0.8001 -1.050036)
			(end 0.8001 1.050036)
			(stroke
				(width 0.1)
				(type default)
			)
			(layer "F.Fab")
		)
		(fp_line
			(start 0.8001 1.050036)
			(end -0.8001 1.050036)
			(stroke
				(width 0.1)
				(type default)
			)
			(layer "F.Fab")
		)
		(fp_poly
			(pts
				(xy -2.458974 -0.508) (xy -2.458974 0.508) (xy -1.442974 0)
			)
			(stroke
				(width 0)
				(type default)
			)
			(fill yes)
			(layer "F.Fab")
		)
		(pad "1_2" smd circle
			(at -0.374904 0 90)
			(size 0 0)
			(layers "F.Cu" "F.Mask" "F.Paste")
			(net "P3V3_AUX")
		)
		(pad "3" smd rect
			(at -0.499872 0.999998)
			(size 0.254 0.7112)
			(layers "F.Cu" "F.Mask" "F.Paste")
			(net "GND")
		)
		(pad "4" smd rect
			(at 0 0.999998)
			(size 0.254 0.7112)
			(layers "F.Cu" "F.Mask" "F.Paste")
			(net "P3V3_SSD10_CO_ILIMIT")
		)
		(pad "5" smd rect
			(at 0.499872 0.999998)
			(size 0.254 0.7112)
			(layers "F.Cu" "F.Mask" "F.Paste")
			(net "P3V3_SSD10_CO_MODE")
		)
		(pad "6_7" smd circle
			(at 0.374904 0 270)
			(size 0 0)
			(layers "F.Cu" "F.Mask" "F.Paste")
			(net "P3V3_SSD10")
		)
		(pad "8" smd rect
			(at 0.499872 -0.999998)
			(size 0.254 0.7112)
			(layers "F.Cu" "F.Mask" "F.Paste")
			(net "P3V3_SSD10_CO_GATE")
		)
		(pad "9" smd rect
			(at 0 -0.999998)
			(size 0.254 0.7112)
			(layers "F.Cu" "F.Mask" "F.Paste")
			(net "P3V3_SSD10_CO_EN")
		)
		(pad "10" smd rect
			(at -0.499872 -0.999998)
			(size 0.254 0.7112)
			(layers "F.Cu" "F.Mask" "F.Paste")
			(net "P3V3_SSD10_CO_DV_DT")
		)
	)
	(footprint ""
		(layer "F.Cu")
		(at 248.187972 -45.704252 90)
		(property "Reference" "R593"
			(at 0 0 90)
			(layer "F.SilkS")
			(hide yes)
			(effects
				(font
					(size 1.27 1.27)
				)
			)
		)
		(property "Value" ""
			(at 0 0 90)
			(layer "F.Fab")
			(effects
				(font
					(size 1.27 1.27)
				)
			)
		)
		(duplicate_pad_numbers_are_jumpers no)
		(fp_line
			(start 3.937508 -1.8796)
			(end -3.937508 -1.8796)
			(stroke
				(width 0.1524)
				(type default)
			)
			(layer "F.SilkS")
		)
		(fp_line
			(start -3.937508 -1.8796)
			(end -3.937508 1.8796)
			(stroke
				(width 0.1524)
				(type default)
			)
			(layer "F.SilkS")
		)
		(fp_line
			(start 3.937508 1.8796)
			(end 3.937508 -1.8796)
			(stroke
				(width 0.1524)
				(type default)
			)
			(layer "F.SilkS")
		)
		(fp_line
			(start -3.937508 1.8796)
			(end 3.937508 1.8796)
			(stroke
				(width 0.1524)
				(type default)
			)
			(layer "F.SilkS")
		)
		(fp_line
			(start 3.275076 -1.674876)
			(end -3.275076 -1.674876)
			(stroke
				(width 0.1)
				(type default)
			)
			(layer "F.Fab")
		)
		(fp_line
			(start -3.275076 -1.674876)
			(end -3.275076 1.674876)
			(stroke
				(width 0.1)
				(type default)
			)
			(layer "F.Fab")
		)
		(fp_line
			(start 3.275076 1.674876)
			(end 3.275076 -1.674876)
			(stroke
				(width 0.1)
				(type default)
			)
			(layer "F.Fab")
		)
		(fp_line
			(start -3.275076 1.674876)
			(end 3.275076 1.674876)
			(stroke
				(width 0.1)
				(type default)
			)
			(layer "F.Fab")
		)
		(pad "1" smd rect
			(at -2.350008 0 90)
			(size 2.921 3.5052)
			(layers "F.Cu" "F.Mask" "F.Paste")
			(net "P12V_SSD8")
		)
		(pad "2" smd rect
			(at 2.350008 0 90)
			(size 2.921 3.5052)
			(layers "F.Cu" "F.Mask" "F.Paste")
			(net "P12V_SSD8_R")
		)
	)
	(footprint ""
		(layer "F.Cu")
		(at 95.818198 -95.31477 90)
		(property "Reference" "R855"
			(at 0 0 90)
			(layer "F.SilkS")
			(hide yes)
			(effects
				(font
					(size 1.27 1.27)
				)
			)
		)
		(property "Value" ""
			(at 0 0 90)
			(layer "F.Fab")
			(effects
				(font
					(size 1.27 1.27)
				)
			)
		)
		(duplicate_pad_numbers_are_jumpers no)
		(fp_line
			(start 0.7874 -0.4064)
			(end 0.7874 0.4064)
			(stroke
				(width 0.1524)
				(type default)
			)
			(layer "F.SilkS")
		)
		(fp_line
			(start -0.7874 -0.4064)
			(end 0.7874 -0.4064)
			(stroke
				(width 0.1524)
				(type default)
			)
			(layer "F.SilkS")
		)
		(fp_line
			(start 0.7874 0.4064)
			(end -0.7874 0.4064)
			(stroke
				(width 0.1524)
				(type default)
			)
			(layer "F.SilkS")
		)
		(fp_line
			(start -0.7874 0.4064)
			(end -0.7874 -0.4064)
			(stroke
				(width 0.1524)
				(type default)
			)
			(layer "F.SilkS")
		)
		(fp_line
			(start -0.12065 -0.305054)
			(end -0.12065 -0.2794)
			(stroke
				(width 0.1)
				(type default)
			)
			(layer "F.Fab")
		)
		(fp_line
			(start -0.67945 -0.305054)
			(end -0.12065 -0.305054)
			(stroke
				(width 0.1)
				(type default)
			)
			(layer "F.Fab")
		)
		(fp_line
			(start 0.67945 -0.3048)
			(end 0.67945 0.3048)
			(stroke
				(width 0.1)
				(type default)
			)
			(layer "F.Fab")
		)
		(fp_line
			(start 0.12065 -0.3048)
			(end 0.67945 -0.3048)
			(stroke
				(width 0.1)
				(type default)
			)
			(layer "F.Fab")
		)
		(fp_line
			(start 0.12065 -0.2794)
			(end 0.12065 -0.3048)
			(stroke
				(width 0.1)
				(type default)
			)
			(layer "F.Fab")
		)
		(fp_line
			(start -0.12065 -0.2794)
			(end 0.12065 -0.2794)
			(stroke
				(width 0.1)
				(type default)
			)
			(layer "F.Fab")
		)
		(fp_line
			(start 0.120396 0.2794)
			(end -0.12065 0.2794)
			(stroke
				(width 0.1)
				(type default)
			)
			(layer "F.Fab")
		)
		(fp_line
			(start -0.12065 0.2794)
			(end -0.12065 0.3048)
			(stroke
				(width 0.1)
				(type default)
			)
			(layer "F.Fab")
		)
		(fp_line
			(start 0.67945 0.3048)
			(end 0.120396 0.3048)
			(stroke
				(width 0.1)
				(type default)
			)
			(layer "F.Fab")
		)
		(fp_line
			(start 0.120396 0.3048)
			(end 0.120396 0.2794)
			(stroke
				(width 0.1)
				(type default)
			)
			(layer "F.Fab")
		)
		(fp_line
			(start -0.12065 0.3048)
			(end -0.67945 0.3048)
			(stroke
				(width 0.1)
				(type default)
			)
			(layer "F.Fab")
		)
		(fp_line
			(start -0.67945 0.3048)
			(end -0.67945 -0.305054)
			(stroke
				(width 0.1)
				(type default)
			)
			(layer "F.Fab")
		)
		(pad "1" smd circle
			(at -0.40005 0 90)
			(size 0 0)
			(layers "F.Cu" "F.Mask" "F.Paste")
			(net "P3V3_AUX")
		)
		(pad "2" smd circle
			(at 0.40005 0 90)
			(size 0 0)
			(layers "F.Cu" "F.Mask" "F.Paste")
			(net "PWRGD_P12V_NIC1")
		)
	)
	(footprint ""
		(layer "F.Cu")
		(at 227.104956 -305.118262)
		(property "Reference" "PC231"
			(at 0 0 0)
			(layer "F.SilkS")
			(hide yes)
			(effects
				(font
					(size 1.27 1.27)
				)
			)
		)
		(property "Value" ""
			(at 0 0 0)
			(layer "F.Fab")
			(effects
				(font
					(size 1.27 1.27)
				)
			)
		)
		(duplicate_pad_numbers_are_jumpers no)
		(fp_line
			(start -0.7874 -0.4064)
			(end 0.7874 -0.4064)
			(stroke
				(width 0.1524)
				(type default)
			)
			(layer "F.SilkS")
		)
		(fp_line
			(start -0.7874 0.4064)
			(end -0.7874 -0.4064)
			(stroke
				(width 0.1524)
				(type default)
			)
			(layer "F.SilkS")
		)
		(fp_line
			(start 0.7874 -0.4064)
			(end 0.7874 0.4064)
			(stroke
				(width 0.1524)
				(type default)
			)
			(layer "F.SilkS")
		)
		(fp_line
			(start 0.7874 0.4064)
			(end -0.7874 0.4064)
			(stroke
				(width 0.1524)
				(type default)
			)
			(layer "F.SilkS")
		)
		(fp_line
			(start -0.67945 -0.305054)
			(end -0.12065 -0.305054)
			(stroke
				(width 0.1)
				(type default)
			)
			(layer "F.Fab")
		)
		(fp_line
			(start -0.67945 0.3048)
			(end -0.67945 -0.305054)
			(stroke
				(width 0.1)
				(type default)
			)
			(layer "F.Fab")
		)
		(fp_line
			(start -0.12065 -0.305054)
			(end -0.12065 -0.2794)
			(stroke
				(width 0.1)
				(type default)
			)
			(layer "F.Fab")
		)
		(fp_line
			(start -0.12065 -0.2794)
			(end 0.12065 -0.2794)
			(stroke
				(width 0.1)
				(type default)
			)
			(layer "F.Fab")
		)
		(fp_line
			(start -0.12065 0.2794)
			(end -0.12065 0.3048)
			(stroke
				(width 0.1)
				(type default)
			)
			(layer "F.Fab")
		)
		(fp_line
			(start -0.12065 0.3048)
			(end -0.67945 0.3048)
			(stroke
				(width 0.1)
				(type default)
			)
			(layer "F.Fab")
		)
		(fp_line
			(start 0.120396 0.2794)
			(end -0.12065 0.2794)
			(stroke
				(width 0.1)
				(type default)
			)
			(layer "F.Fab")
		)
		(fp_line
			(start 0.120396 0.3048)
			(end 0.120396 0.2794)
			(stroke
				(width 0.1)
				(type default)
			)
			(layer "F.Fab")
		)
		(fp_line
			(start 0.12065 -0.3048)
			(end 0.67945 -0.3048)
			(stroke
				(width 0.1)
				(type default)
			)
			(layer "F.Fab")
		)
		(fp_line
			(start 0.12065 -0.2794)
			(end 0.12065 -0.3048)
			(stroke
				(width 0.1)
				(type default)
			)
			(layer "F.Fab")
		)
		(fp_line
			(start 0.67945 -0.3048)
			(end 0.67945 0.3048)
			(stroke
				(width 0.1)
				(type default)
			)
			(layer "F.Fab")
		)
		(fp_line
			(start 0.67945 0.3048)
			(end 0.120396 0.3048)
			(stroke
				(width 0.1)
				(type default)
			)
			(layer "F.Fab")
		)
		(pad "1" smd circle
			(at -0.40005 0)
			(size 0 0)
			(layers "F.Cu" "F.Mask" "F.Paste")
			(net "SW_P1V25_PEX1_BT")
		)
		(pad "2" smd circle
			(at 0.40005 0)
			(size 0 0)
			(layers "F.Cu" "F.Mask" "F.Paste")
			(net "SW_P1V25_PEX1_PH")
		)
	)
	(footprint ""
		(layer "F.Cu")
		(at 411.86735 -171.675806)
		(property "Reference" "R355"
			(at 0 0 0)
			(layer "F.SilkS")
			(hide yes)
			(effects
				(font
					(size 1.27 1.27)
				)
			)
		)
		(property "Value" ""
			(at 0 0 0)
			(layer "F.Fab")
			(effects
				(font
					(size 1.27 1.27)
				)
			)
		)
		(duplicate_pad_numbers_are_jumpers no)
		(fp_line
			(start -0.7874 -0.4064)
			(end 0.7874 -0.4064)
			(stroke
				(width 0.1524)
				(type default)
			)
			(layer "F.SilkS")
		)
		(fp_line
			(start -0.7874 0.4064)
			(end -0.7874 -0.4064)
			(stroke
				(width 0.1524)
				(type default)
			)
			(layer "F.SilkS")
		)
		(fp_line
			(start 0.7874 -0.4064)
			(end 0.7874 0.4064)
			(stroke
				(width 0.1524)
				(type default)
			)
			(layer "F.SilkS")
		)
		(fp_line
			(start 0.7874 0.4064)
			(end -0.7874 0.4064)
			(stroke
				(width 0.1524)
				(type default)
			)
			(layer "F.SilkS")
		)
		(fp_line
			(start -0.67945 -0.305054)
			(end -0.12065 -0.305054)
			(stroke
				(width 0.1)
				(type default)
			)
			(layer "F.Fab")
		)
		(fp_line
			(start -0.67945 0.3048)
			(end -0.67945 -0.305054)
			(stroke
				(width 0.1)
				(type default)
			)
			(layer "F.Fab")
		)
		(fp_line
			(start -0.12065 -0.305054)
			(end -0.12065 -0.2794)
			(stroke
				(width 0.1)
				(type default)
			)
			(layer "F.Fab")
		)
		(fp_line
			(start -0.12065 -0.2794)
			(end 0.12065 -0.2794)
			(stroke
				(width 0.1)
				(type default)
			)
			(layer "F.Fab")
		)
		(fp_line
			(start -0.12065 0.2794)
			(end -0.12065 0.3048)
			(stroke
				(width 0.1)
				(type default)
			)
			(layer "F.Fab")
		)
		(fp_line
			(start -0.12065 0.3048)
			(end -0.67945 0.3048)
			(stroke
				(width 0.1)
				(type default)
			)
			(layer "F.Fab")
		)
		(fp_line
			(start 0.120396 0.2794)
			(end -0.12065 0.2794)
			(stroke
				(width 0.1)
				(type default)
			)
			(layer "F.Fab")
		)
		(fp_line
			(start 0.120396 0.3048)
			(end 0.120396 0.2794)
			(stroke
				(width 0.1)
				(type default)
			)
			(layer "F.Fab")
		)
		(fp_line
			(start 0.12065 -0.3048)
			(end 0.67945 -0.3048)
			(stroke
				(width 0.1)
				(type default)
			)
			(layer "F.Fab")
		)
		(fp_line
			(start 0.12065 -0.2794)
			(end 0.12065 -0.3048)
			(stroke
				(width 0.1)
				(type default)
			)
			(layer "F.Fab")
		)
		(fp_line
			(start 0.67945 -0.3048)
			(end 0.67945 0.3048)
			(stroke
				(width 0.1)
				(type default)
			)
			(layer "F.Fab")
		)
		(fp_line
			(start 0.67945 0.3048)
			(end 0.120396 0.3048)
			(stroke
				(width 0.1)
				(type default)
			)
			(layer "F.Fab")
		)
		(pad "1" smd circle
			(at -0.40005 0)
			(size 0 0)
			(layers "F.Cu" "F.Mask" "F.Paste")
			(net "P3V3_NIC6")
		)
		(pad "2" smd circle
			(at 0.40005 0)
			(size 0 0)
			(layers "F.Cu" "F.Mask" "F.Paste")
			(net "HP_NIC6_PWRGD")
		)
	)
)
